(kicad_pcb
	(version 20260206)
	(generator "pcbnew")
	(generator_version "10.0")
	(general
		(thickness 1.6)
		(legacy_teardrops no)
	)
	(paper "A4")
	(title_block
		(title "netronome-mezz — pcbd0082-001_rev01_jul9_a.brd")
		(comment 1 "Open CloudServer (Microsoft) / footprints 254-262 of 714")
	)
	(layers
		(0 "F.Cu" signal "TOP")
		(4 "In1.Cu" signal "02_GND")
		(6 "In2.Cu" signal "03_SIG")
		(8 "In3.Cu" signal "04_SIG")
		(10 "In4.Cu" signal "05_GND")
		(12 "In5.Cu" signal "06_PWR1")
		(14 "In6.Cu" signal "07_SIG")
		(16 "In7.Cu" signal "08_SIG")
		(18 "In8.Cu" signal "09_GND")
		(2 "B.Cu" signal "BOTTOM")
		(9 "F.Adhes" user "F.Adhesive")
		(11 "B.Adhes" user "B.Adhesive")
		(13 "F.Paste" user "Package Geometry/Pastemask Top")
		(15 "B.Paste" user "Package Geometry/Pastemask Bottom")
		(5 "F.SilkS" user "Ref Des/Silkscreen Top")
		(7 "B.SilkS" user "Ref Des/Silkscreen Bottom")
		(1 "F.Mask" user "Board Geometry/Soldermask Top")
		(3 "B.Mask" user "Board Geometry/Soldermask Bottom")
		(17 "Dwgs.User" user "User.Drawings")
		(19 "Cmts.User" user "User.Comments")
		(21 "Eco1.User" user "User.Eco1")
		(23 "Eco2.User" user "User.Eco2")
		(25 "Edge.Cuts" user "Board Geometry/Outline")
		(27 "Margin" user)
		(31 "F.CrtYd" user "Package Geometry/Place Bound Top")
		(29 "B.CrtYd" user "Package Geometry/Place Bound Bottom")
		(35 "F.Fab" user "Ref Des/Assembly Top")
		(33 "B.Fab" user "Ref Des/Assembly Bottom")
		(45 "User.4" user "COMPVAL_TYPE_BOTTOM")
	)
	(footprint ""
		(layer "F.Cu")
		(at 27.051 13.97 -90)
		(property "Reference" "R263"
			(at 0 0 270)
			(layer "F.SilkS")
			(hide yes)
			(effects
				(font
					(size 1.27 1.27)
				)
			)
		)
		(property "Value" "39.0"
			(at -0.148158 1.3462 0)
			(unlocked yes)
			(layer "F.Fab")
			(hide yes)
			(effects
				(font
					(size 1.27 0.9652)
					(thickness 0.000001)
				)
				(justify left)
			)
		)
		(property "Device Type" "REST0108"
			(at -0.148158 1.3462 0)
			(unlocked yes)
			(layer "F.Fab")
			(hide yes)
			(effects
				(font
					(size 1.27 0.9652)
					(thickness 0.000001)
				)
				(justify left)
			)
		)
		(duplicate_pad_numbers_are_jumpers no)
		(fp_poly
			(pts
				(xy 0.635 1.0668) (xy 0.635 -1.0668) (xy -0.635 -1.0668) (xy -0.635 1.0668)
			)
			(stroke
				(width 0)
				(type default)
			)
			(fill no)
			(layer "F.CrtYd")
		)
		(fp_line
			(start -0.254 0.508)
			(end -0.254 -0.508)
			(stroke
				(width 0.0254)
				(type default)
			)
			(layer "F.Fab")
		)
		(fp_line
			(start 0.254 0.508)
			(end -0.254 0.508)
			(stroke
				(width 0.0254)
				(type default)
			)
			(layer "F.Fab")
		)
		(fp_line
			(start -0.254 -0.508)
			(end 0.254 -0.508)
			(stroke
				(width 0.0254)
				(type default)
			)
			(layer "F.Fab")
		)
		(fp_line
			(start 0.254 -0.508)
			(end 0.254 0.508)
			(stroke
				(width 0.0254)
				(type default)
			)
			(layer "F.Fab")
		)
		(pad "1" smd rect
			(at 0 -0.4191 270)
			(size 0.508 0.5334)
			(layers "F.Cu" "F.Mask" "F.Paste")
			(net "_NFP_JTAG_ARM_TDO")
		)
		(pad "2" smd rect
			(at 0 0.4191 270)
			(size 0.508 0.5334)
			(layers "F.Cu" "F.Mask" "F.Paste")
			(net "NFP_JTAG_ARM_TDO")
		)
		(zone
			(layer "F.Cu")
			(hatch none 0.5)
			(connect_pads
				(clearance 0)
			)
			(min_thickness 0.25)
			(keepout
				(tracks not_allowed)
				(vias allowed)
				(pads allowed)
				(copperpour not_allowed)
				(footprints allowed)
			)
			(placement
				(enabled no)
				(sheetname "")
			)
			(fill
				(thermal_gap 0.5)
				(thermal_bridge_width 0.5)
				(island_removal_mode 0)
			)
			(polygon
				(pts
					(xy 27.0764 13.9954) (xy 27.0256 13.9954) (xy 27.0256 13.9446) (xy 27.0764 13.9446)
				)
			)
		)
	)
	(footprint ""
		(layer "F.Cu")
		(at 73.152 25.4 180)
		(property "Reference" "R340"
			(at 0.86233 -0.254 90)
			(unlocked yes)
			(layer "F.SilkS")
			(effects
				(font
					(size 0.7874 0.5842)
					(thickness 0.127)
				)
				(justify left)
			)
		)
		(property "Value" "4.75K"
			(at -0.148158 1.3462 270)
			(unlocked yes)
			(layer "F.Fab")
			(hide yes)
			(effects
				(font
					(size 1.27 0.9652)
					(thickness 0.000001)
				)
				(justify left)
			)
		)
		(property "Device Type" "REST4024"
			(at -0.148158 1.3462 270)
			(unlocked yes)
			(layer "F.Fab")
			(hide yes)
			(effects
				(font
					(size 1.27 0.9652)
					(thickness 0.000001)
				)
				(justify left)
			)
		)
		(duplicate_pad_numbers_are_jumpers no)
		(fp_poly
			(pts
				(xy 0.635 1.0668) (xy 0.635 -1.0668) (xy -0.635 -1.0668) (xy -0.635 1.0668)
			)
			(stroke
				(width 0)
				(type default)
			)
			(fill no)
			(layer "F.CrtYd")
		)
		(fp_line
			(start 0.254 0.508)
			(end -0.254 0.508)
			(stroke
				(width 0.0254)
				(type default)
			)
			(layer "F.Fab")
		)
		(fp_line
			(start 0.254 -0.508)
			(end 0.254 0.508)
			(stroke
				(width 0.0254)
				(type default)
			)
			(layer "F.Fab")
		)
		(fp_line
			(start -0.254 0.508)
			(end -0.254 -0.508)
			(stroke
				(width 0.0254)
				(type default)
			)
			(layer "F.Fab")
		)
		(fp_line
			(start -0.254 -0.508)
			(end 0.254 -0.508)
			(stroke
				(width 0.0254)
				(type default)
			)
			(layer "F.Fab")
		)
		(pad "1" smd rect
			(at 0 -0.4191 180)
			(size 0.508 0.5334)
			(layers "F.Cu" "F.Mask" "F.Paste")
			(net "12N3291")
		)
		(pad "2" smd rect
			(at 0 0.4191 180)
			(size 0.508 0.5334)
			(layers "F.Cu" "F.Mask" "F.Paste")
			(net "DDR_VDDQ")
		)
		(zone
			(layer "F.Cu")
			(hatch none 0.5)
			(connect_pads
				(clearance 0)
			)
			(min_thickness 0.25)
			(keepout
				(tracks not_allowed)
				(vias allowed)
				(pads allowed)
				(copperpour not_allowed)
				(footprints allowed)
			)
			(placement
				(enabled no)
				(sheetname "")
			)
			(fill
				(thermal_gap 0.5)
				(thermal_bridge_width 0.5)
				(island_removal_mode 0)
			)
			(polygon
				(pts
					(xy 73.1266 25.4254) (xy 73.1266 25.3746) (xy 73.1774 25.3746) (xy 73.1774 25.4254)
				)
			)
		)
	)
	(footprint ""
		(layer "F.Cu")
		(at 15.621 1.397)
		(property "Reference" "R390"
			(at 0.53467 -0.762 90)
			(unlocked yes)
			(layer "F.SilkS")
			(effects
				(font
					(size 0.7874 0.5842)
					(thickness 0.127)
				)
				(justify left)
			)
		)
		(property "Value" "0"
			(at -0.148158 1.3462 90)
			(unlocked yes)
			(layer "F.Fab")
			(hide yes)
			(effects
				(font
					(size 1.27 0.9652)
					(thickness 0.000001)
				)
				(justify left)
			)
		)
		(property "Device Type" "REST1111"
			(at -0.148158 1.3462 90)
			(unlocked yes)
			(layer "F.Fab")
			(hide yes)
			(effects
				(font
					(size 1.27 0.9652)
					(thickness 0.000001)
				)
				(justify left)
			)
		)
		(duplicate_pad_numbers_are_jumpers no)
		(fp_poly
			(pts
				(xy 0.635 1.0668) (xy 0.635 -1.0668) (xy -0.635 -1.0668) (xy -0.635 1.0668)
			)
			(stroke
				(width 0)
				(type default)
			)
			(fill no)
			(layer "F.CrtYd")
		)
		(fp_line
			(start -0.254 -0.508)
			(end 0.254 -0.508)
			(stroke
				(width 0.0254)
				(type default)
			)
			(layer "F.Fab")
		)
		(fp_line
			(start -0.254 0.508)
			(end -0.254 -0.508)
			(stroke
				(width 0.0254)
				(type default)
			)
			(layer "F.Fab")
		)
		(fp_line
			(start 0.254 -0.508)
			(end 0.254 0.508)
			(stroke
				(width 0.0254)
				(type default)
			)
			(layer "F.Fab")
		)
		(fp_line
			(start 0.254 0.508)
			(end -0.254 0.508)
			(stroke
				(width 0.0254)
				(type default)
			)
			(layer "F.Fab")
		)
		(pad "1" smd rect
			(at 0 -0.4191)
			(size 0.508 0.5334)
			(layers "F.Cu" "F.Mask" "F.Paste")
			(net "CPLD_SMBUS_SCL")
		)
		(pad "2" smd rect
			(at 0 0.4191)
			(size 0.508 0.5334)
			(layers "F.Cu" "F.Mask" "F.Paste")
			(net "SMBUS_SCL")
		)
		(zone
			(layer "F.Cu")
			(hatch none 0.5)
			(connect_pads
				(clearance 0)
			)
			(min_thickness 0.25)
			(keepout
				(tracks not_allowed)
				(vias allowed)
				(pads allowed)
				(copperpour not_allowed)
				(footprints allowed)
			)
			(placement
				(enabled no)
				(sheetname "")
			)
			(fill
				(thermal_gap 0.5)
				(thermal_bridge_width 0.5)
				(island_removal_mode 0)
			)
			(polygon
				(pts
					(xy 15.6464 1.3716) (xy 15.6464 1.4224) (xy 15.5956 1.4224) (xy 15.5956 1.3716)
				)
			)
		)
	)
	(footprint ""
		(layer "F.Cu")
		(at 73.851008 6.698996)
		(property "Reference" "V_A-DQ08"
			(at 0 0 0)
			(layer "F.SilkS")
			(hide yes)
			(effects
				(font
					(size 1.27 1.27)
				)
			)
		)
		(property "Value" ""
			(at 0 0 0)
			(layer "F.Fab")
			(effects
				(font
					(size 1.27 1.27)
				)
			)
		)
		(duplicate_pad_numbers_are_jumpers no)
		(pad "1" thru_hole circle
			(at 0 0)
			(size 0.762 0.762)
			(drill 0.20574)
			(layers "*.Cu" "*.Mask")
			(remove_unused_layers no)
			(net "DDR0_32A_DQ8")
			(clearance 0.127)
			(thermal_gap 0.127)
			(padstack
				(mode front_inner_back)
				(layer "Inner"
					(shape circle)
					(size 0.4572 0.4572)
					(clearance 0.1143)
				)
				(layer "B.Cu"
					(shape circle)
					(size 0.4572 0.4572)
					(clearance 0.1143)
				)
			)
		)
	)
	(footprint ""
		(layer "F.Cu")
		(at 63.5 46.60646)
		(property "Reference" "C127"
			(at 0 0 0)
			(layer "F.SilkS")
			(hide yes)
			(effects
				(font
					(size 1.27 1.27)
				)
			)
		)
		(property "Value" "0.1UF"
			(at -0.091846 0.2921 90)
			(unlocked yes)
			(layer "F.Fab")
			(hide yes)
			(effects
				(font
					(size 0.7874 0.5842)
					(thickness 0.2032)
				)
				(justify left)
			)
		)
		(property "Device Type" "CAPC0073"
			(at -0.091846 0.2921 90)
			(unlocked yes)
			(layer "F.Fab")
			(hide yes)
			(effects
				(font
					(size 0.7874 0.5842)
					(thickness 0.2032)
				)
				(justify left)
			)
		)
		(duplicate_pad_numbers_are_jumpers no)
		(fp_poly
			(pts
				(xy 0.635 1.0668) (xy 0.635 -1.0668) (xy -0.635 -1.0668) (xy -0.635 1.0668)
			)
			(stroke
				(width 0)
				(type default)
			)
			(fill no)
			(layer "F.CrtYd")
		)
		(fp_line
			(start -0.254 -0.508)
			(end 0.254 -0.508)
			(stroke
				(width 0.0254)
				(type default)
			)
			(layer "F.Fab")
		)
		(fp_line
			(start -0.254 0.508)
			(end -0.254 -0.508)
			(stroke
				(width 0.0254)
				(type default)
			)
			(layer "F.Fab")
		)
		(fp_line
			(start 0.254 -0.508)
			(end 0.254 0.508)
			(stroke
				(width 0.0254)
				(type default)
			)
			(layer "F.Fab")
		)
		(fp_line
			(start 0.254 0.508)
			(end -0.254 0.508)
			(stroke
				(width 0.0254)
				(type default)
			)
			(layer "F.Fab")
		)
		(pad "1" smd rect
			(at 0 -0.4191)
			(size 0.508 0.5334)
			(layers "F.Cu" "F.Mask" "F.Paste")
			(net "11N1981")
		)
		(pad "2" smd rect
			(at 0 0.4191)
			(size 0.508 0.5334)
			(layers "F.Cu" "F.Mask" "F.Paste")
			(net "11N1952")
		)
		(zone
			(layer "F.Cu")
			(hatch none 0.5)
			(connect_pads
				(clearance 0)
			)
			(min_thickness 0.25)
			(keepout
				(tracks not_allowed)
				(vias allowed)
				(pads allowed)
				(copperpour not_allowed)
				(footprints allowed)
			)
			(placement
				(enabled no)
				(sheetname "")
			)
			(fill
				(thermal_gap 0.5)
				(thermal_bridge_width 0.5)
				(island_removal_mode 0)
			)
			(polygon
				(pts
					(xy 63.5254 46.58106) (xy 63.5254 46.63186) (xy 63.4746 46.63186) (xy 63.4746 46.58106)
				)
			)
		)
	)
	(footprint ""
		(layer "F.Cu")
		(at 84.6836 42.418)
		(property "Reference" "C129"
			(at 0.81407 1.651 90)
			(unlocked yes)
			(layer "F.SilkS")
			(effects
				(font
					(size 0.7874 0.5842)
					(thickness 0.127)
				)
				(justify left)
			)
		)
		(property "Value" "0.1UF"
			(at -0.091846 0.2921 90)
			(unlocked yes)
			(layer "F.Fab")
			(hide yes)
			(effects
				(font
					(size 0.7874 0.5842)
					(thickness 0.2032)
				)
				(justify left)
			)
		)
		(property "Device Type" "CAPC0073"
			(at -0.091846 0.2921 90)
			(unlocked yes)
			(layer "F.Fab")
			(hide yes)
			(effects
				(font
					(size 0.7874 0.5842)
					(thickness 0.2032)
				)
				(justify left)
			)
		)
		(duplicate_pad_numbers_are_jumpers no)
		(fp_poly
			(pts
				(xy 0.635 1.0668) (xy 0.635 -1.0668) (xy -0.635 -1.0668) (xy -0.635 1.0668)
			)
			(stroke
				(width 0)
				(type default)
			)
			(fill no)
			(layer "F.CrtYd")
		)
		(fp_line
			(start -0.254 -0.508)
			(end 0.254 -0.508)
			(stroke
				(width 0.0254)
				(type default)
			)
			(layer "F.Fab")
		)
		(fp_line
			(start -0.254 0.508)
			(end -0.254 -0.508)
			(stroke
				(width 0.0254)
				(type default)
			)
			(layer "F.Fab")
		)
		(fp_line
			(start 0.254 -0.508)
			(end 0.254 0.508)
			(stroke
				(width 0.0254)
				(type default)
			)
			(layer "F.Fab")
		)
		(fp_line
			(start 0.254 0.508)
			(end -0.254 0.508)
			(stroke
				(width 0.0254)
				(type default)
			)
			(layer "F.Fab")
		)
		(pad "1" smd rect
			(at 0 -0.4191)
			(size 0.508 0.5334)
			(layers "F.Cu" "F.Mask" "F.Paste")
			(net "11N2181")
		)
		(pad "2" smd rect
			(at 0 0.4191)
			(size 0.508 0.5334)
			(layers "F.Cu" "F.Mask" "F.Paste")
			(net "11N2175")
		)
		(zone
			(layer "F.Cu")
			(hatch none 0.5)
			(connect_pads
				(clearance 0)
			)
			(min_thickness 0.25)
			(keepout
				(tracks not_allowed)
				(vias allowed)
				(pads allowed)
				(copperpour not_allowed)
				(footprints allowed)
			)
			(placement
				(enabled no)
				(sheetname "")
			)
			(fill
				(thermal_gap 0.5)
				(thermal_bridge_width 0.5)
				(island_removal_mode 0)
			)
			(polygon
				(pts
					(xy 84.709 42.3926) (xy 84.709 42.4434) (xy 84.6582 42.4434) (xy 84.6582 42.3926)
				)
			)
		)
	)
	(footprint ""
		(layer "F.Cu")
		(at 47.498 46.609 90)
		(property "Reference" "R400"
			(at 0 0 90)
			(layer "F.SilkS")
			(hide yes)
			(effects
				(font
					(size 1.27 1.27)
				)
			)
		)
		(property "Value" "4.75K"
			(at -0.148158 1.3462 180)
			(unlocked yes)
			(layer "F.Fab")
			(hide yes)
			(effects
				(font
					(size 1.27 0.9652)
					(thickness 0.000001)
				)
				(justify left)
			)
		)
		(property "Device Type" "REST4024"
			(at -0.148158 1.3462 180)
			(unlocked yes)
			(layer "F.Fab")
			(hide yes)
			(effects
				(font
					(size 1.27 0.9652)
					(thickness 0.000001)
				)
				(justify left)
			)
		)
		(duplicate_pad_numbers_are_jumpers no)
		(fp_poly
			(pts
				(xy 0.635 1.0668) (xy 0.635 -1.0668) (xy -0.635 -1.0668) (xy -0.635 1.0668)
			)
			(stroke
				(width 0)
				(type default)
			)
			(fill no)
			(layer "F.CrtYd")
		)
		(fp_line
			(start 0.254 -0.508)
			(end 0.254 0.508)
			(stroke
				(width 0.0254)
				(type default)
			)
			(layer "F.Fab")
		)
		(fp_line
			(start -0.254 -0.508)
			(end 0.254 -0.508)
			(stroke
				(width 0.0254)
				(type default)
			)
			(layer "F.Fab")
		)
		(fp_line
			(start 0.254 0.508)
			(end -0.254 0.508)
			(stroke
				(width 0.0254)
				(type default)
			)
			(layer "F.Fab")
		)
		(fp_line
			(start -0.254 0.508)
			(end -0.254 -0.508)
			(stroke
				(width 0.0254)
				(type default)
			)
			(layer "F.Fab")
		)
		(pad "1" smd rect
			(at 0 -0.4191 90)
			(size 0.508 0.5334)
			(layers "F.Cu" "F.Mask" "F.Paste")
			(net "GND")
		)
		(pad "2" smd rect
			(at 0 0.4191 90)
			(size 0.508 0.5334)
			(layers "F.Cu" "F.Mask" "F.Paste")
			(net "VDD_5.0V_EN")
		)
		(zone
			(layer "F.Cu")
			(hatch none 0.5)
			(connect_pads
				(clearance 0)
			)
			(min_thickness 0.25)
			(keepout
				(tracks not_allowed)
				(vias allowed)
				(pads allowed)
				(copperpour not_allowed)
				(footprints allowed)
			)
			(placement
				(enabled no)
				(sheetname "")
			)
			(fill
				(thermal_gap 0.5)
				(thermal_bridge_width 0.5)
				(island_removal_mode 0)
			)
			(polygon
				(pts
					(xy 47.4726 46.5836) (xy 47.5234 46.5836) (xy 47.5234 46.6344) (xy 47.4726 46.6344)
				)
			)
		)
	)
	(footprint ""
		(layer "F.Cu")
		(at 23.241 29.337 180)
		(property "Reference" "R64"
			(at 0 0 180)
			(layer "F.SilkS")
			(hide yes)
			(effects
				(font
					(size 1.27 1.27)
				)
			)
		)
		(property "Value" "4.75K"
			(at -0.148158 1.3462 270)
			(unlocked yes)
			(layer "F.Fab")
			(hide yes)
			(effects
				(font
					(size 1.27 0.9652)
					(thickness 0.000001)
				)
				(justify left)
			)
		)
		(property "Device Type" "REST4024"
			(at -0.148158 1.3462 270)
			(unlocked yes)
			(layer "F.Fab")
			(hide yes)
			(effects
				(font
					(size 1.27 0.9652)
					(thickness 0.000001)
				)
				(justify left)
			)
		)
		(duplicate_pad_numbers_are_jumpers no)
		(fp_poly
			(pts
				(xy 0.635 1.0668) (xy 0.635 -1.0668) (xy -0.635 -1.0668) (xy -0.635 1.0668)
			)
			(stroke
				(width 0)
				(type default)
			)
			(fill no)
			(layer "F.CrtYd")
		)
		(fp_line
			(start 0.254 0.508)
			(end -0.254 0.508)
			(stroke
				(width 0.0254)
				(type default)
			)
			(layer "F.Fab")
		)
		(fp_line
			(start 0.254 -0.508)
			(end 0.254 0.508)
			(stroke
				(width 0.0254)
				(type default)
			)
			(layer "F.Fab")
		)
		(fp_line
			(start -0.254 0.508)
			(end -0.254 -0.508)
			(stroke
				(width 0.0254)
				(type default)
			)
			(layer "F.Fab")
		)
		(fp_line
			(start -0.254 -0.508)
			(end 0.254 -0.508)
			(stroke
				(width 0.0254)
				(type default)
			)
			(layer "F.Fab")
		)
		(pad "1" smd rect
			(at 0 -0.4191 180)
			(size 0.508 0.5334)
			(layers "F.Cu" "F.Mask" "F.Paste")
			(net "NFP_CPLD_PRGM_JTAG_TCK")
		)
		(pad "2" smd rect
			(at 0 0.4191 180)
			(size 0.508 0.5334)
			(layers "F.Cu" "F.Mask" "F.Paste")
			(net "GND")
		)
		(zone
			(layer "F.Cu")
			(hatch none 0.5)
			(connect_pads
				(clearance 0)
			)
			(min_thickness 0.25)
			(keepout
				(tracks not_allowed)
				(vias allowed)
				(pads allowed)
				(copperpour not_allowed)
				(footprints allowed)
			)
			(placement
				(enabled no)
				(sheetname "")
			)
			(fill
				(thermal_gap 0.5)
				(thermal_bridge_width 0.5)
				(island_removal_mode 0)
			)
			(polygon
				(pts
					(xy 23.2156 29.3624) (xy 23.2156 29.3116) (xy 23.2664 29.3116) (xy 23.2664 29.3624)
				)
			)
		)
	)
	(footprint ""
		(layer "F.Cu")
		(at 80.0862 22.987 180)
		(property "Reference" "R224"
			(at 0 0 180)
			(layer "F.SilkS")
			(hide yes)
			(effects
				(font
					(size 1.27 1.27)
				)
			)
		)
		(property "Value" "39.0"
			(at -0.148158 1.3462 270)
			(unlocked yes)
			(layer "F.Fab")
			(hide yes)
			(effects
				(font
					(size 1.27 0.9652)
					(thickness 0.000001)
				)
				(justify left)
			)
		)
		(property "Device Type" "REST0108"
			(at -0.148158 1.3462 270)
			(unlocked yes)
			(layer "F.Fab")
			(hide yes)
			(effects
				(font
					(size 1.27 0.9652)
					(thickness 0.000001)
				)
				(justify left)
			)
		)
		(duplicate_pad_numbers_are_jumpers no)
		(fp_poly
			(pts
				(xy 0.635 1.0668) (xy 0.635 -1.0668) (xy -0.635 -1.0668) (xy -0.635 1.0668)
			)
			(stroke
				(width 0)
				(type default)
			)
			(fill no)
			(layer "F.CrtYd")
		)
		(fp_line
			(start 0.254 0.508)
			(end -0.254 0.508)
			(stroke
				(width 0.0254)
				(type default)
			)
			(layer "F.Fab")
		)
		(fp_line
			(start 0.254 -0.508)
			(end 0.254 0.508)
			(stroke
				(width 0.0254)
				(type default)
			)
			(layer "F.Fab")
		)
		(fp_line
			(start -0.254 0.508)
			(end -0.254 -0.508)
			(stroke
				(width 0.0254)
				(type default)
			)
			(layer "F.Fab")
		)
		(fp_line
			(start -0.254 -0.508)
			(end 0.254 -0.508)
			(stroke
				(width 0.0254)
				(type default)
			)
			(layer "F.Fab")
		)
		(pad "1" smd rect
			(at 0 -0.4191 180)
			(size 0.508 0.5334)
			(layers "F.Cu" "F.Mask" "F.Paste")
			(net "DDR0_32A_BA0")
		)
		(pad "2" smd rect
			(at 0 0.4191 180)
			(size 0.508 0.5334)
			(layers "F.Cu" "F.Mask" "F.Paste")
			(net "DDR_VTT")
		)
		(zone
			(layer "F.Cu")
			(hatch none 0.5)
			(connect_pads
				(clearance 0)
			)
			(min_thickness 0.25)
			(keepout
				(tracks not_allowed)
				(vias allowed)
				(pads allowed)
				(copperpour not_allowed)
				(footprints allowed)
			)
			(placement
				(enabled no)
				(sheetname "")
			)
			(fill
				(thermal_gap 0.5)
				(thermal_bridge_width 0.5)
				(island_removal_mode 0)
			)
			(polygon
				(pts
					(xy 80.0608 23.0124) (xy 80.0608 22.9616) (xy 80.1116 22.9616) (xy 80.1116 23.0124)
				)
			)
		)
	)
)
